# S9S_MB_2U (Grand Teton) — schematic netlist excerpt (pin names and nets, part order shuffled) for the footprints in the layout excerpt that follows; sources: Cadence DE-HDL packaged netlist, KiCad conversion of 03242023_DA0F0TMBIJ0_F0T_Motherboard_J_brd_V01_OCP.brd

C1365  Q_CAP  22UF 4V 20% X6S  pkg C0402  page 80 : A = PVNN_MAIN_CPU1 ; B = GND
C517  Q_CAP  47UF 4V 20% X6S  pkg C0805  page 76 : A = PVCCFA_EHV_FIVRA_CPU0 ; B = GND
PR250  Q_RES  2.2 1% CHIP  pkg 0402LF  page 294 : A = PVCCFA_EHV_CPU1_PVCC ; B = PVCCFA_EHV_CPU1_VDD1

(kicad_pcb
	(version 20260206)
	(generator "pcbnew")
	(generator_version "10.0")
	(general
		(thickness 1.6)
		(legacy_teardrops no)
	)
	(paper "A4")
	(title_block
		(title "03242023_DA0F0TMBIJ0_F0T_Motherboard_J_brd_V01_OCP.brd")
		(comment 1 "Grand Teton / footprints 4503-4505 of 6105")
	)
	(layers
		(0 "F.Cu" signal "TOP")
		(4 "In1.Cu" signal "GND")
		(6 "In2.Cu" signal "IN1")
		(8 "In3.Cu" signal "GND1")
		(10 "In4.Cu" signal "IN2")
		(12 "In5.Cu" signal "GND2")
		(14 "In6.Cu" signal "IN3")
		(16 "In7.Cu" signal "GND3")
		(18 "In8.Cu" signal "VCC")
		(20 "In9.Cu" signal "VCC1")
		(22 "In10.Cu" signal "GND4")
		(24 "In11.Cu" signal "IN4")
		(26 "In12.Cu" signal "GND5")
		(28 "In13.Cu" signal "IN5")
		(30 "In14.Cu" signal "GND6")
		(32 "In15.Cu" signal "IN6")
		(34 "In16.Cu" signal "GND7")
		(2 "B.Cu" signal "BOTTOM")
		(9 "F.Adhes" user "F.Adhesive")
		(11 "B.Adhes" user "B.Adhesive")
		(13 "F.Paste" user "Package Geometry/Pastemask Top")
		(15 "B.Paste" user "Package Geometry/Pastemask Bottom")
		(5 "F.SilkS" user "Ref Des/Silkscreen Top")
		(7 "B.SilkS" user "Ref Des/Silkscreen Bottom")
		(1 "F.Mask" user "Board Geometry/Soldermask Top")
		(3 "B.Mask" user "Board Geometry/Soldermask Bottom")
		(17 "Dwgs.User" user "User.Drawings")
		(19 "Cmts.User" user "User.Comments")
		(21 "Eco1.User" user "User.Eco1")
		(23 "Eco2.User" user "User.Eco2")
		(25 "Edge.Cuts" user "Board Geometry/Outline")
		(27 "Margin" user)
		(31 "F.CrtYd" user "Package Geometry/Place Bound Top")
		(29 "B.CrtYd" user "Package Geometry/Place Bound Bottom")
		(35 "F.Fab" user "Ref Des/Assembly Top")
		(33 "B.Fab" user "Ref Des/Assembly Bottom")
	)
	(footprint ""
		(layer "B.Cu")
		(at 36.765992 -178.63058 180)
		(property "Reference" "C1365"
			(at 0 0 0)
			(layer "B.SilkS")
			(hide yes)
			(effects
				(font
					(size 1.27 1.27)
				)
				(justify mirror)
			)
		)
		(property "Value" ""
			(at 0 0 0)
			(layer "B.Fab")
			(effects
				(font
					(size 1.27 1.27)
				)
				(justify mirror)
			)
		)
		(duplicate_pad_numbers_are_jumpers no)
		(fp_line
			(start 0.7874 0.4064)
			(end 0.7874 -0.4064)
			(stroke
				(width 0.1524)
				(type default)
			)
			(layer "B.SilkS")
		)
		(fp_line
			(start 0.7874 -0.4064)
			(end -0.7874 -0.4064)
			(stroke
				(width 0.1524)
				(type default)
			)
			(layer "B.SilkS")
		)
		(fp_line
			(start -0.7874 0.4064)
			(end 0.7874 0.4064)
			(stroke
				(width 0.1524)
				(type default)
			)
			(layer "B.SilkS")
		)
		(fp_line
			(start -0.7874 -0.4064)
			(end -0.7874 0.4064)
			(stroke
				(width 0.1524)
				(type default)
			)
			(layer "B.SilkS")
		)
		(fp_line
			(start 0.67945 0.3048)
			(end 0.67945 -0.305054)
			(stroke
				(width 0.1)
				(type default)
			)
			(layer "B.Fab")
		)
		(fp_line
			(start 0.67945 -0.305054)
			(end 0.12065 -0.305054)
			(stroke
				(width 0.1)
				(type default)
			)
			(layer "B.Fab")
		)
		(fp_line
			(start 0.12065 0.3048)
			(end 0.67945 0.3048)
			(stroke
				(width 0.1)
				(type default)
			)
			(layer "B.Fab")
		)
		(fp_line
			(start 0.12065 0.2794)
			(end 0.12065 0.3048)
			(stroke
				(width 0.1)
				(type default)
			)
			(layer "B.Fab")
		)
		(fp_line
			(start 0.12065 -0.2794)
			(end -0.12065 -0.2794)
			(stroke
				(width 0.1)
				(type default)
			)
			(layer "B.Fab")
		)
		(fp_line
			(start 0.12065 -0.305054)
			(end 0.12065 -0.2794)
			(stroke
				(width 0.1)
				(type default)
			)
			(layer "B.Fab")
		)
		(fp_line
			(start -0.120396 0.3048)
			(end -0.120396 0.2794)
			(stroke
				(width 0.1)
				(type default)
			)
			(layer "B.Fab")
		)
		(fp_line
			(start -0.120396 0.2794)
			(end 0.12065 0.2794)
			(stroke
				(width 0.1)
				(type default)
			)
			(layer "B.Fab")
		)
		(fp_line
			(start -0.12065 -0.2794)
			(end -0.12065 -0.3048)
			(stroke
				(width 0.1)
				(type default)
			)
			(layer "B.Fab")
		)
		(fp_line
			(start -0.12065 -0.3048)
			(end -0.67945 -0.3048)
			(stroke
				(width 0.1)
				(type default)
			)
			(layer "B.Fab")
		)
		(fp_line
			(start -0.67945 0.3048)
			(end -0.120396 0.3048)
			(stroke
				(width 0.1)
				(type default)
			)
			(layer "B.Fab")
		)
		(fp_line
			(start -0.67945 -0.3048)
			(end -0.67945 0.3048)
			(stroke
				(width 0.1)
				(type default)
			)
			(layer "B.Fab")
		)
		(pad "1" smd circle
			(at 0.40005 0)
			(size 0 0)
			(layers "B.Cu" "B.Mask" "B.Paste")
			(net "PVNN_MAIN_CPU1")
		)
		(pad "2" smd circle
			(at -0.40005 0)
			(size 0 0)
			(layers "B.Cu" "B.Mask" "B.Paste")
			(net "GND")
		)
	)
	(footprint ""
		(layer "B.Cu")
		(at 51.14544 -170.495468 90)
		(property "Reference" "PR250"
			(at 0 0 90)
			(layer "B.SilkS")
			(hide yes)
			(effects
				(font
					(size 1.27 1.27)
				)
				(justify mirror)
			)
		)
		(property "Value" ""
			(at 0 0 90)
			(layer "B.Fab")
			(effects
				(font
					(size 1.27 1.27)
				)
				(justify mirror)
			)
		)
		(duplicate_pad_numbers_are_jumpers no)
		(fp_line
			(start 0.7874 -0.4064)
			(end -0.7874 -0.4064)
			(stroke
				(width 0.1524)
				(type default)
			)
			(layer "B.SilkS")
		)
		(fp_line
			(start -0.7874 -0.4064)
			(end -0.7874 0.4064)
			(stroke
				(width 0.1524)
				(type default)
			)
			(layer "B.SilkS")
		)
		(fp_line
			(start 0.7874 0.4064)
			(end 0.7874 -0.4064)
			(stroke
				(width 0.1524)
				(type default)
			)
			(layer "B.SilkS")
		)
		(fp_line
			(start -0.7874 0.4064)
			(end 0.7874 0.4064)
			(stroke
				(width 0.1524)
				(type default)
			)
			(layer "B.SilkS")
		)
		(fp_line
			(start 0.67945 -0.305054)
			(end 0.12065 -0.305054)
			(stroke
				(width 0.1)
				(type default)
			)
			(layer "B.Fab")
		)
		(fp_line
			(start 0.12065 -0.305054)
			(end 0.12065 -0.2794)
			(stroke
				(width 0.1)
				(type default)
			)
			(layer "B.Fab")
		)
		(fp_line
			(start -0.12065 -0.3048)
			(end -0.67945 -0.3048)
			(stroke
				(width 0.1)
				(type default)
			)
			(layer "B.Fab")
		)
		(fp_line
			(start -0.67945 -0.3048)
			(end -0.67945 0.3048)
			(stroke
				(width 0.1)
				(type default)
			)
			(layer "B.Fab")
		)
		(fp_line
			(start 0.12065 -0.2794)
			(end -0.12065 -0.2794)
			(stroke
				(width 0.1)
				(type default)
			)
			(layer "B.Fab")
		)
		(fp_line
			(start -0.12065 -0.2794)
			(end -0.12065 -0.3048)
			(stroke
				(width 0.1)
				(type default)
			)
			(layer "B.Fab")
		)
		(fp_line
			(start 0.12065 0.2794)
			(end 0.12065 0.3048)
			(stroke
				(width 0.1)
				(type default)
			)
			(layer "B.Fab")
		)
		(fp_line
			(start -0.120396 0.2794)
			(end 0.12065 0.2794)
			(stroke
				(width 0.1)
				(type default)
			)
			(layer "B.Fab")
		)
		(fp_line
			(start 0.67945 0.3048)
			(end 0.67945 -0.305054)
			(stroke
				(width 0.1)
				(type default)
			)
			(layer "B.Fab")
		)
		(fp_line
			(start 0.12065 0.3048)
			(end 0.67945 0.3048)
			(stroke
				(width 0.1)
				(type default)
			)
			(layer "B.Fab")
		)
		(fp_line
			(start -0.120396 0.3048)
			(end -0.120396 0.2794)
			(stroke
				(width 0.1)
				(type default)
			)
			(layer "B.Fab")
		)
		(fp_line
			(start -0.67945 0.3048)
			(end -0.120396 0.3048)
			(stroke
				(width 0.1)
				(type default)
			)
			(layer "B.Fab")
		)
		(pad "1" smd circle
			(at 0.40005 0 270)
			(size 0 0)
			(layers "B.Cu" "B.Mask" "B.Paste")
			(net "PVCCFA_EHV_CPU1_PVCC")
		)
		(pad "2" smd circle
			(at -0.40005 0 270)
			(size 0 0)
			(layers "B.Cu" "B.Mask" "B.Paste")
			(net "PVCCFA_EHV_CPU1_VDD1")
		)
	)
	(footprint ""
		(layer "B.Cu")
		(at 308.823614 -258.379976 -90)
		(property "Reference" "C517"
			(at 0 0 90)
			(layer "B.SilkS")
			(hide yes)
			(effects
				(font
					(size 1.27 1.27)
				)
				(justify mirror)
			)
		)
		(property "Value" ""
			(at 0 0 90)
			(layer "B.Fab")
			(effects
				(font
					(size 1.27 1.27)
				)
				(justify mirror)
			)
		)
		(duplicate_pad_numbers_are_jumpers no)
		(fp_line
			(start -1.524 0.762)
			(end 1.524 0.762)
			(stroke
				(width 0.1524)
				(type default)
			)
			(layer "B.SilkS")
		)
		(fp_line
			(start 1.524 0.762)
			(end 1.524 -0.762)
			(stroke
				(width 0.1524)
				(type default)
			)
			(layer "B.SilkS")
		)
		(fp_line
			(start -1.524 -0.762)
			(end -1.524 0.762)
			(stroke
				(width 0.1524)
				(type default)
			)
			(layer "B.SilkS")
		)
		(fp_line
			(start 1.524 -0.762)
			(end -1.524 -0.762)
			(stroke
				(width 0.1524)
				(type default)
			)
			(layer "B.SilkS")
		)
		(fp_line
			(start -1.1049 0.724916)
			(end -1.1049 -0.724916)
			(stroke
				(width 0.1)
				(type default)
			)
			(layer "B.Fab")
		)
		(fp_line
			(start 1.1049 0.724916)
			(end -1.1049 0.724916)
			(stroke
				(width 0.1)
				(type default)
			)
			(layer "B.Fab")
		)
		(fp_line
			(start -1.1049 -0.724916)
			(end 1.1049 -0.724916)
			(stroke
				(width 0.1)
				(type default)
			)
			(layer "B.Fab")
		)
		(fp_line
			(start 1.1049 -0.724916)
			(end 1.1049 0.724916)
			(stroke
				(width 0.1)
				(type default)
			)
			(layer "B.Fab")
		)
		(pad "1" smd rect
			(at 0.889 0 270)
			(size 1.016 1.27)
			(layers "B.Cu" "B.Mask" "B.Paste")
			(net "PVCCFA_EHV_FIVRA_CPU0")
		)
		(pad "2" smd rect
			(at -0.889 0 270)
			(size 1.016 1.27)
			(layers "B.Cu" "B.Mask" "B.Paste")
			(net "GND")
		)
	)
)
